(kicad_pcb
	(version 20260206)
	(generator "pcbnew")
	(generator_version "10.0")
	(general
		(thickness 1.6)
		(legacy_teardrops no)
	)
	(paper "A4")
	(title_block
		(title "Bryce Canyon_R.DPB_16317-1_OCP.brd")
		(comment 1 "Bryce Canyon / footprints 215-222 of 2099")
	)
	(layers
		(0 "F.Cu" signal "TOP")
		(4 "In1.Cu" signal "L2GND")
		(6 "In2.Cu" signal "L3")
		(8 "In3.Cu" signal "L4VCC")
		(10 "In4.Cu" signal "L5VCC")
		(12 "In5.Cu" signal "L6")
		(14 "In6.Cu" signal "L7GND")
		(2 "B.Cu" signal "BOTTOM")
		(9 "F.Adhes" user "F.Adhesive")
		(11 "B.Adhes" user "B.Adhesive")
		(13 "F.Paste" user "Package Geometry/Pastemask Top")
		(15 "B.Paste" user "Package Geometry/Pastemask Bottom")
		(5 "F.SilkS" user "Ref Des/Silkscreen Top")
		(7 "B.SilkS" user "Ref Des/Silkscreen Bottom")
		(1 "F.Mask" user "Board Geometry/Soldermask Top")
		(3 "B.Mask" user "Board Geometry/Soldermask Bottom")
		(17 "Dwgs.User" user "User.Drawings")
		(19 "Cmts.User" user "User.Comments")
		(21 "Eco1.User" user "User.Eco1")
		(23 "Eco2.User" user "User.Eco2")
		(25 "Edge.Cuts" user "Board Geometry/Outline")
		(27 "Margin" user)
		(31 "F.CrtYd" user "Package Geometry/Place Bound Top")
		(29 "B.CrtYd" user "Package Geometry/Place Bound Bottom")
		(35 "F.Fab" user "Ref Des/Assembly Top")
		(33 "B.Fab" user "Ref Des/Assembly Bottom")
	)
	(footprint ""
		(layer "F.Cu")
		(at 455.93 -152.908 180)
		(property "Reference" "C316"
			(at 0 0 180)
			(layer "F.SilkS")
			(hide yes)
			(effects
				(font
					(size 1.27 1.27)
				)
			)
		)
		(property "Value" "SC1U16V3KX-5GP"
			(at 0 -2.8194 180)
			(unlocked yes)
			(layer "F.Fab")
			(hide yes)
			(effects
				(font
					(size 1.016 1.016)
					(thickness 0.1524)
				)
			)
		)
		(property "Device Type" "C603H36"
			(at 0 -4.3434 180)
			(unlocked yes)
			(layer "F.Fab")
			(hide yes)
			(effects
				(font
					(size 1.016 1.016)
					(thickness 0.1524)
				)
			)
		)
		(duplicate_pad_numbers_are_jumpers no)
		(fp_line
			(start 0.508 0)
			(end -0.508 0)
			(stroke
				(width 0.2032)
				(type default)
			)
			(layer "F.SilkS")
		)
		(fp_rect
			(start -0.5842 1.3335)
			(end 0.5842 -1.3335)
			(stroke
				(width 0)
				(type default)
			)
			(fill no)
			(layer "F.CrtYd")
		)
		(fp_rect
			(start -0.5842 1.3335)
			(end 0.5842 -1.3335)
			(stroke
				(width 0)
				(type default)
			)
			(fill no)
			(layer "F.Fab")
		)
		(pad "1" smd custom
			(at 0 -0.762 180)
			(size 0.2159 0.2159)
			(layers "F.Cu" "F.Mask" "F.Paste")
			(net "P5V_HDD22")
			(options
				(clearance outline)
				(anchor circle)
			)
			(primitives
				(gr_poly
					(pts
						(arc
							(start -0.3302 -0.4318)
							(mid -0.402042 -0.402042)
							(end -0.4318 -0.3302)
						)
						(arc
							(start -0.4318 0.3302)
							(mid -0.402042 0.402042)
							(end -0.3302 0.4318)
						)
						(arc
							(start 0.3302 0.4318)
							(mid 0.402042 0.402042)
							(end 0.4318 0.3302)
						)
						(arc
							(start 0.4318 -0.3302)
							(mid 0.402042 -0.402042)
							(end 0.3302 -0.4318)
						)
					)
					(width 0)
					(fill yes)
				)
			)
		)
		(pad "2" smd custom
			(at 0 0.762 180)
			(size 0.2159 0.2159)
			(layers "F.Cu" "F.Mask" "F.Paste")
			(net "GND")
			(options
				(clearance outline)
				(anchor circle)
			)
			(primitives
				(gr_poly
					(pts
						(arc
							(start -0.3302 -0.4318)
							(mid -0.402042 -0.402042)
							(end -0.4318 -0.3302)
						)
						(arc
							(start -0.4318 0.3302)
							(mid -0.402042 0.402042)
							(end -0.3302 0.4318)
						)
						(arc
							(start 0.3302 0.4318)
							(mid 0.402042 0.402042)
							(end 0.4318 0.3302)
						)
						(arc
							(start 0.4318 -0.3302)
							(mid 0.402042 -0.402042)
							(end 0.3302 -0.4318)
						)
					)
					(width 0)
					(fill yes)
				)
			)
		)
	)
	(footprint ""
		(layer "F.Cu")
		(at 328.643996 -371.856 -90)
		(property "Reference" "D41"
			(at 0 0 270)
			(layer "F.SilkS")
			(hide yes)
			(effects
				(font
					(size 1.27 1.27)
				)
			)
		)
		(property "Value" "BAS16H-GP"
			(at 0 -5.5372 270)
			(unlocked yes)
			(layer "F.Fab")
			(hide yes)
			(effects
				(font
					(size 1.016 1.016)
					(thickness 0.1524)
				)
			)
		)
		(property "Device Type" "SOD123AKH48"
			(at 0 -7.0612 270)
			(unlocked yes)
			(layer "F.Fab")
			(hide yes)
			(effects
				(font
					(size 1.016 1.016)
					(thickness 0.1524)
				)
			)
		)
		(duplicate_pad_numbers_are_jumpers no)
		(fp_line
			(start 0.889 2.921)
			(end -0.889 2.921)
			(stroke
				(width 0.508)
				(type default)
			)
			(layer "F.SilkS")
		)
		(fp_line
			(start -1.016 2.667)
			(end 1.016 2.667)
			(stroke
				(width 0.1524)
				(type default)
			)
			(layer "F.SilkS")
		)
		(fp_line
			(start 1.016 2.667)
			(end 1.016 -2.667)
			(stroke
				(width 0.1524)
				(type default)
			)
			(layer "F.SilkS")
		)
		(fp_line
			(start -1.016 -2.667)
			(end -1.016 2.667)
			(stroke
				(width 0.1524)
				(type default)
			)
			(layer "F.SilkS")
		)
		(fp_line
			(start 1.016 -2.667)
			(end -1.016 -2.667)
			(stroke
				(width 0.1524)
				(type default)
			)
			(layer "F.SilkS")
		)
		(fp_rect
			(start -1.143 3.175)
			(end 1.143 -2.794)
			(stroke
				(width 0)
				(type default)
			)
			(fill no)
			(layer "F.CrtYd")
		)
		(fp_poly
			(pts
				(xy -1.143 -2.794) (xy 1.143 -2.794) (xy 1.143 3.175) (xy -1.143 3.175)
			)
			(stroke
				(width 0)
				(type default)
			)
			(fill no)
			(layer "F.Fab")
		)
		(pad "A" smd rect
			(at 0 -1.6891 270)
			(size 0.889 1.397)
			(layers "F.Cu" "F.Mask" "F.Paste")
			(net "FAN_2_TACH0")
		)
		(pad "K" smd rect
			(at 0 1.6891 270)
			(size 0.889 1.397)
			(layers "F.Cu" "F.Mask" "F.Paste")
			(net "P12V_IN")
		)
	)
	(footprint ""
		(layer "F.Cu")
		(at 150.114 -42.291)
		(property "Reference" "C399"
			(at 0 0 0)
			(layer "F.SilkS")
			(hide yes)
			(effects
				(font
					(size 1.27 1.27)
				)
			)
		)
		(property "Value" "SC4D7U25V5KX-1-GP"
			(at -0.0762 -6.1214 0)
			(unlocked yes)
			(layer "F.Fab")
			(hide yes)
			(effects
				(font
					(size 1.016 1.016)
					(thickness 0.1524)
				)
			)
		)
		(property "Device Type" "C805H58"
			(at -0.0762 -8.1534 0)
			(unlocked yes)
			(layer "F.Fab")
			(hide yes)
			(effects
				(font
					(size 1.016 1.016)
					(thickness 0.1524)
				)
			)
		)
		(duplicate_pad_numbers_are_jumpers no)
		(fp_line
			(start 0.635 0)
			(end -0.635 0)
			(stroke
				(width 0.508)
				(type default)
			)
			(layer "F.SilkS")
		)
		(fp_rect
			(start -0.9652 1.778)
			(end 0.9652 -1.778)
			(stroke
				(width 0)
				(type default)
			)
			(fill no)
			(layer "F.CrtYd")
		)
		(fp_poly
			(pts
				(xy -0.9652 -1.778) (xy 0.9652 -1.778) (xy 0.9652 1.778) (xy -0.9652 1.778)
			)
			(stroke
				(width 0)
				(type default)
			)
			(fill no)
			(layer "F.Fab")
		)
		(pad "1" smd rect
			(at 0 -0.9652)
			(size 1.397 1.143)
			(layers "F.Cu" "F.Mask" "F.Paste")
			(net "P12V_HDD28")
		)
		(pad "2" smd rect
			(at 0 0.9652)
			(size 1.397 1.143)
			(layers "F.Cu" "F.Mask" "F.Paste")
			(net "GND")
		)
	)
	(footprint ""
		(layer "F.Cu")
		(at 439.037222 -118.613682 -90)
		(property "Reference" "R1164"
			(at 0 0 270)
			(layer "F.SilkS")
			(hide yes)
			(effects
				(font
					(size 1.27 1.27)
				)
			)
		)
		(property "Value" "200KR2F-L-GP"
			(at 0.064008 -3.993896 270)
			(unlocked yes)
			(layer "F.Fab")
			(hide yes)
			(effects
				(font
					(size 1.016 1.016)
					(thickness 0.1524)
				)
			)
		)
		(property "Device Type" "R402H16"
			(at 0.064008 -5.517896 270)
			(unlocked yes)
			(layer "F.Fab")
			(hide yes)
			(effects
				(font
					(size 1.016 1.016)
					(thickness 0.1524)
				)
			)
		)
		(duplicate_pad_numbers_are_jumpers no)
		(fp_line
			(start -0.508 -0.9398)
			(end -0.508 0.9398)
			(stroke
				(width 0.1524)
				(type default)
			)
			(layer "F.SilkS")
		)
		(fp_line
			(start 0.508 -0.9398)
			(end -0.508 -0.9398)
			(stroke
				(width 0.1524)
				(type default)
			)
			(layer "F.SilkS")
		)
		(fp_rect
			(start -0.508 0.9398)
			(end 0.508 -0.9398)
			(stroke
				(width 0)
				(type default)
			)
			(fill no)
			(layer "F.CrtYd")
		)
		(fp_rect
			(start -0.508 0.9398)
			(end 0.508 -0.9398)
			(stroke
				(width 0)
				(type default)
			)
			(fill no)
			(layer "F.Fab")
		)
		(pad "1" smd custom
			(at 0 -0.4445 270)
			(size 0.1397 0.1397)
			(layers "F.Cu" "F.Mask" "F.Paste")
			(net "P5V_B_4_MODE")
			(options
				(clearance outline)
				(anchor circle)
			)
			(primitives
				(gr_poly
					(pts
						(arc
							(start -0.1778 -0.2794)
							(mid -0.249642 -0.249642)
							(end -0.2794 -0.1778)
						)
						(arc
							(start -0.2794 0.1778)
							(mid -0.249642 0.249642)
							(end -0.1778 0.2794)
						)
						(arc
							(start 0.1778 0.2794)
							(mid 0.249642 0.249642)
							(end 0.2794 0.1778)
						)
						(arc
							(start 0.2794 -0.1778)
							(mid 0.249642 -0.249642)
							(end 0.1778 -0.2794)
						)
					)
					(width 0)
					(fill yes)
				)
			)
		)
		(pad "2" smd custom
			(at 0 0.4445 270)
			(size 0.1397 0.1397)
			(layers "F.Cu" "F.Mask" "F.Paste")
			(net "P5V_B_4_PGOOD")
			(options
				(clearance outline)
				(anchor circle)
			)
			(primitives
				(gr_poly
					(pts
						(arc
							(start -0.1778 -0.2794)
							(mid -0.249642 -0.249642)
							(end -0.2794 -0.1778)
						)
						(arc
							(start -0.2794 0.1778)
							(mid -0.249642 0.249642)
							(end -0.1778 0.2794)
						)
						(arc
							(start 0.1778 0.2794)
							(mid 0.249642 0.249642)
							(end 0.2794 0.1778)
						)
						(arc
							(start 0.2794 -0.1778)
							(mid 0.249642 -0.249642)
							(end 0.1778 -0.2794)
						)
					)
					(width 0)
					(fill yes)
				)
			)
		)
	)
	(footprint ""
		(layer "F.Cu")
		(at 244.199918 -243.999766)
		(property "Reference" ""
			(at 0 0 0)
			(layer "F.SilkS")
			(hide yes)
			(effects
				(font
					(size 1.27 1.27)
				)
			)
		)
		(property "Value" "*"
			(at -8.398764 -8.057642 0)
			(unlocked yes)
			(layer "F.Fab")
			(hide yes)
			(effects
				(font
					(size 1.016 1.016)
					(thickness 0.1524)
				)
			)
		)
		(duplicate_pad_numbers_are_jumpers no)
		(fp_poly
			(pts
				(arc
					(start 7.3152 0)
					(mid 0 7.3152)
					(end -7.3152 0)
				)
				(arc
					(start -7.3152 -5.9944)
					(mid 0 -13.3096)
					(end 7.3152 -5.9944)
				)
			)
			(stroke
				(width 0)
				(type default)
			)
			(fill no)
			(layer "B.CrtYd")
		)
		(fp_poly
			(pts
				(arc
					(start 7.3152 0)
					(mid 0 7.3152)
					(end -7.3152 0)
				)
				(arc
					(start -7.3152 -5.9944)
					(mid 0 -13.3096)
					(end 7.3152 -5.9944)
				)
			)
			(stroke
				(width 0)
				(type default)
			)
			(fill no)
			(layer "F.CrtYd")
		)
		(fp_poly
			(pts
				(arc
					(start 7.3152 0)
					(mid 0 7.3152)
					(end -7.3152 0)
				)
				(arc
					(start -7.3152 -5.9944)
					(mid 0 -13.3096)
					(end 7.3152 -5.9944)
				)
			)
			(stroke
				(width 0)
				(type default)
			)
			(fill no)
			(layer "B.Fab")
		)
		(fp_poly
			(pts
				(arc
					(start 7.3152 0)
					(mid 0 7.3152)
					(end -7.3152 0)
				)
				(arc
					(start -7.3152 -5.9944)
					(mid 0 -13.3096)
					(end 7.3152 -5.9944)
				)
			)
			(stroke
				(width 0)
				(type default)
			)
			(fill no)
			(layer "F.Fab")
		)
		(pad "1" thru_hole oval
			(at 0 0)
			(size 14.0208 20.0152)
			(drill 0.0254
				(offset 0 -2.9972)
			)
			(layers "*.Cu" "*.Mask")
			(remove_unused_layers no)
			(net "Net_20")
			(clearance -1.002284)
			(thermal_gap 0.1524)
			(padstack
				(mode front_inner_back)
				(layer "Inner"
					(shape custom)
					(size 2.928012 2.928012)
					(options
						(anchor circle)
					)
					(primitives
						(gr_poly
							(pts
								(arc
									(start 4.571746 -2.084324)
									(mid 0.000333 7.430372)
									(end -4.571492 -2.084324)
								)
								(arc
									(start -4.571492 -2.084324)
									(mid -3.570296 -3.611977)
									(end -2.875026 -5.30098)
								)
								(arc
									(start -2.875026 -5.30098)
									(mid 0.000217 -7.43089)
									(end 2.87528 -5.30098)
								)
								(arc
									(start 2.87528 -5.30098)
									(mid 3.570511 -3.611956)
									(end 4.571746 -2.084324)
								)
							)
							(width 0)
							(fill yes)
						)
					)
					(clearance 0.1524)
				)
				(layer "B.Cu"
					(shape oval)
					(size 14.0208 20.0152)
					(offset 0 -2.9972)
					(clearance -1.002284)
				)
			)
		)
		(zone
			(layers "F.Cu" "B.Cu" "In1.Cu" "In2.Cu" "In3.Cu" "In4.Cu" "In5.Cu" "In6.Cu")
			(hatch none 0.5)
			(connect_pads
				(clearance 0)
			)
			(min_thickness 0.25)
			(keepout
				(tracks not_allowed)
				(vias allowed)
				(pads allowed)
				(copperpour not_allowed)
				(footprints allowed)
			)
			(placement
				(enabled no)
				(sheetname "")
			)
			(fill
				(thermal_gap 0.5)
				(thermal_bridge_width 0.5)
				(island_removal_mode 0)
			)
			(polygon
				(pts
					(arc
						(start 237.189518 -249.994166)
						(mid 244.199918 -257.004566)
						(end 251.210318 -249.994166)
					)
					(arc
						(start 251.210318 -243.999766)
						(mid 244.199918 -236.989366)
						(end 237.189518 -243.999766)
					)
				)
			)
		)
	)
	(footprint ""
		(layer "F.Cu")
		(at 469.773 -251.587 180)
		(property "Reference" "D11"
			(at 0 0 180)
			(layer "F.SilkS")
			(hide yes)
			(effects
				(font
					(size 1.27 1.27)
				)
			)
		)
		(property "Value" "RB551V30-GP"
			(at 0 -6.7818 180)
			(unlocked yes)
			(layer "F.Fab")
			(hide yes)
			(effects
				(font
					(size 1.016 1.016)
					(thickness 0.1524)
				)
			)
		)
		(property "Device Type" "SOD323AKH38"
			(at 0 -8.6868 180)
			(unlocked yes)
			(layer "F.Fab")
			(hide yes)
			(effects
				(font
					(size 1.016 1.016)
					(thickness 0.1524)
				)
			)
		)
		(duplicate_pad_numbers_are_jumpers no)
		(fp_line
			(start 0.889 2.159)
			(end -0.889 2.159)
			(stroke
				(width 0.1524)
				(type default)
			)
			(layer "F.SilkS")
		)
		(fp_line
			(start 0.889 -1.9304)
			(end 0.889 2.159)
			(stroke
				(width 0.1524)
				(type default)
			)
			(layer "F.SilkS")
		)
		(fp_line
			(start 0.762 2.0574)
			(end -0.762 2.0574)
			(stroke
				(width 0.508)
				(type default)
			)
			(layer "F.SilkS")
		)
		(fp_line
			(start -0.889 2.159)
			(end -0.889 -1.9304)
			(stroke
				(width 0.1524)
				(type default)
			)
			(layer "F.SilkS")
		)
		(fp_line
			(start -0.889 -1.9304)
			(end 0.889 -1.9304)
			(stroke
				(width 0.1524)
				(type default)
			)
			(layer "F.SilkS")
		)
		(fp_rect
			(start -1.016 2.3114)
			(end 1.016 -2.0066)
			(stroke
				(width 0)
				(type default)
			)
			(fill no)
			(layer "F.CrtYd")
		)
		(fp_poly
			(pts
				(xy -1.016 -2.0066) (xy 1.016 -2.0066) (xy 1.016 2.3114) (xy -1.016 2.3114)
			)
			(stroke
				(width 0)
				(type default)
			)
			(fill no)
			(layer "F.Fab")
		)
		(pad "A" smd rect
			(at 0 -1.143 180)
			(size 0.5588 1.016)
			(layers "F.Cu" "F.Mask" "F.Paste")
			(net "SW_HDD_R11")
		)
		(pad "K" smd rect
			(at 0 1.143 180)
			(size 0.5588 1.016)
			(layers "F.Cu" "F.Mask" "F.Paste")
			(net "SW_HDD_N11")
		)
	)
	(footprint ""
		(layer "F.Cu")
		(at 45.599858 -118.324376 180)
		(property "Reference" "R1132"
			(at 0 0 180)
			(layer "F.SilkS")
			(hide yes)
			(effects
				(font
					(size 1.27 1.27)
				)
			)
		)
		(property "Value" "0R2J-2-GP"
			(at 0.064008 -3.993896 180)
			(unlocked yes)
			(layer "F.Fab")
			(hide yes)
			(effects
				(font
					(size 1.016 1.016)
					(thickness 0.1524)
				)
			)
		)
		(property "Device Type" "R402H16"
			(at 0.064008 -5.517896 180)
			(unlocked yes)
			(layer "F.Fab")
			(hide yes)
			(effects
				(font
					(size 1.016 1.016)
					(thickness 0.1524)
				)
			)
		)
		(duplicate_pad_numbers_are_jumpers no)
		(fp_line
			(start 0.508 -0.9398)
			(end -0.508 -0.9398)
			(stroke
				(width 0.1524)
				(type default)
			)
			(layer "F.SilkS")
		)
		(fp_line
			(start -0.508 -0.9398)
			(end -0.508 0.9398)
			(stroke
				(width 0.1524)
				(type default)
			)
			(layer "F.SilkS")
		)
		(fp_rect
			(start -0.508 0.9398)
			(end 0.508 -0.9398)
			(stroke
				(width 0)
				(type default)
			)
			(fill no)
			(layer "F.CrtYd")
		)
		(fp_rect
			(start -0.508 0.9398)
			(end 0.508 -0.9398)
			(stroke
				(width 0)
				(type default)
			)
			(fill no)
			(layer "F.Fab")
		)
		(pad "1" smd custom
			(at 0 -0.4445 180)
			(size 0.1397 0.1397)
			(layers "F.Cu" "F.Mask" "F.Paste")
			(net "P5V_B_2_ROVP")
			(options
				(clearance outline)
				(anchor circle)
			)
			(primitives
				(gr_poly
					(pts
						(arc
							(start -0.1778 -0.2794)
							(mid -0.249642 -0.249642)
							(end -0.2794 -0.1778)
						)
						(arc
							(start -0.2794 0.1778)
							(mid -0.249642 0.249642)
							(end -0.1778 0.2794)
						)
						(arc
							(start 0.1778 0.2794)
							(mid 0.249642 0.249642)
							(end 0.2794 0.1778)
						)
						(arc
							(start 0.2794 -0.1778)
							(mid 0.249642 -0.249642)
							(end 0.1778 -0.2794)
						)
					)
					(width 0)
					(fill yes)
				)
			)
		)
		(pad "2" smd custom
			(at 0 0.4445 180)
			(size 0.1397 0.1397)
			(layers "F.Cu" "F.Mask" "F.Paste")
			(net "AGND_P5V_B_2")
			(options
				(clearance outline)
				(anchor circle)
			)
			(primitives
				(gr_poly
					(pts
						(arc
							(start -0.1778 -0.2794)
							(mid -0.249642 -0.249642)
							(end -0.2794 -0.1778)
						)
						(arc
							(start -0.2794 0.1778)
							(mid -0.249642 0.249642)
							(end -0.1778 0.2794)
						)
						(arc
							(start 0.1778 0.2794)
							(mid 0.249642 0.249642)
							(end 0.2794 0.1778)
						)
						(arc
							(start 0.2794 -0.1778)
							(mid 0.249642 -0.249642)
							(end 0.1778 -0.2794)
						)
					)
					(width 0)
					(fill yes)
				)
			)
		)
	)
	(footprint ""
		(layer "F.Cu")
		(at 425.228004 -371.856 -90)
		(property "Reference" "D43"
			(at 0 0 270)
			(layer "F.SilkS")
			(hide yes)
			(effects
				(font
					(size 1.27 1.27)
				)
			)
		)
		(property "Value" "BAS16H-GP"
			(at 0 -5.5372 270)
			(unlocked yes)
			(layer "F.Fab")
			(hide yes)
			(effects
				(font
					(size 1.016 1.016)
					(thickness 0.1524)
				)
			)
		)
		(property "Device Type" "SOD123AKH48"
			(at 0 -7.0612 270)
			(unlocked yes)
			(layer "F.Fab")
			(hide yes)
			(effects
				(font
					(size 1.016 1.016)
					(thickness 0.1524)
				)
			)
		)
		(duplicate_pad_numbers_are_jumpers no)
		(fp_line
			(start 0.889 2.921)
			(end -0.889 2.921)
			(stroke
				(width 0.508)
				(type default)
			)
			(layer "F.SilkS")
		)
		(fp_line
			(start -1.016 2.667)
			(end 1.016 2.667)
			(stroke
				(width 0.1524)
				(type default)
			)
			(layer "F.SilkS")
		)
		(fp_line
			(start 1.016 2.667)
			(end 1.016 -2.667)
			(stroke
				(width 0.1524)
				(type default)
			)
			(layer "F.SilkS")
		)
		(fp_line
			(start -1.016 -2.667)
			(end -1.016 2.667)
			(stroke
				(width 0.1524)
				(type default)
			)
			(layer "F.SilkS")
		)
		(fp_line
			(start 1.016 -2.667)
			(end -1.016 -2.667)
			(stroke
				(width 0.1524)
				(type default)
			)
			(layer "F.SilkS")
		)
		(fp_rect
			(start -1.143 3.175)
			(end 1.143 -2.794)
			(stroke
				(width 0)
				(type default)
			)
			(fill no)
			(layer "F.CrtYd")
		)
		(fp_poly
			(pts
				(xy -1.143 -2.794) (xy 1.143 -2.794) (xy 1.143 3.175) (xy -1.143 3.175)
			)
			(stroke
				(width 0)
				(type default)
			)
			(fill no)
			(layer "F.Fab")
		)
		(pad "A" smd rect
			(at 0 -1.6891 270)
			(size 0.889 1.397)
			(layers "F.Cu" "F.Mask" "F.Paste")
			(net "FAN_3_TACH0")
		)
		(pad "K" smd rect
			(at 0 1.6891 270)
			(size 0.889 1.397)
			(layers "F.Cu" "F.Mask" "F.Paste")
			(net "P12V_IN")
		)
	)
)
